(kicad_pcb
	(version 20260206)
	(generator "pcbnew")
	(generator_version "10.0")
	(general
		(thickness 1.6)
		(legacy_teardrops no)
	)
	(paper "A4")
	(title_block
		(title "Wiwynn_Tioga_Pass_MB.brd")
		(comment 1 "Tioga Pass / footprints 1411-1417 of 4770")
	)
	(layers
		(0 "F.Cu" signal "TOP")
		(4 "In1.Cu" signal "L2GND")
		(6 "In2.Cu" signal "L3")
		(8 "In3.Cu" signal "L4GND")
		(10 "In4.Cu" signal "L5")
		(12 "In5.Cu" signal "L6GND")
		(14 "In6.Cu" signal "L7VCC")
		(16 "In7.Cu" signal "L8VCC")
		(18 "In8.Cu" signal "L9GND")
		(20 "In9.Cu" signal "L10")
		(22 "In10.Cu" signal "L11GND")
		(24 "In11.Cu" signal "L12")
		(26 "In12.Cu" signal "L13GND")
		(2 "B.Cu" signal "BOTTOM")
		(9 "F.Adhes" user "F.Adhesive")
		(11 "B.Adhes" user "B.Adhesive")
		(13 "F.Paste" user "Package Geometry/Pastemask Top")
		(15 "B.Paste" user "Package Geometry/Pastemask Bottom")
		(5 "F.SilkS" user "Ref Des/Silkscreen Top")
		(7 "B.SilkS" user "Ref Des/Silkscreen Bottom")
		(1 "F.Mask" user "Board Geometry/Soldermask Top")
		(3 "B.Mask" user "Board Geometry/Soldermask Bottom")
		(17 "Dwgs.User" user "User.Drawings")
		(19 "Cmts.User" user "User.Comments")
		(21 "Eco1.User" user "User.Eco1")
		(23 "Eco2.User" user "User.Eco2")
		(25 "Edge.Cuts" user "Board Geometry/Outline")
		(27 "Margin" user)
		(31 "F.CrtYd" user "Package Geometry/Place Bound Top")
		(29 "B.CrtYd" user "Package Geometry/Place Bound Bottom")
		(35 "F.Fab" user "Ref Des/Assembly Top")
		(33 "B.Fab" user "Ref Des/Assembly Bottom")
	)
	(footprint ""
		(layer "F.Cu")
		(at 27.990292 -55.771288 -90)
		(property "Reference" "R1E14"
			(at 0 0 270)
			(layer "F.SilkS")
			(hide yes)
			(effects
				(font
					(size 1.27 1.27)
				)
			)
		)
		(property "Value" ""
			(at 0 0 270)
			(layer "F.Fab")
			(effects
				(font
					(size 1.27 1.27)
				)
			)
		)
		(duplicate_pad_numbers_are_jumpers no)
		(fp_poly
			(pts
				(xy -0.2794 -0.1016) (xy 0.2794 -0.1016) (xy 0.2794 0.9906) (xy -0.2794 0.9906)
			)
			(stroke
				(width 0)
				(type default)
			)
			(fill no)
			(layer "F.CrtYd")
		)
		(fp_line
			(start -0.2794 0.9906)
			(end 0.2794 0.9906)
			(stroke
				(width 0.1)
				(type default)
			)
			(layer "F.Fab")
		)
		(fp_line
			(start 0.2794 0.9906)
			(end 0.2794 -0.1016)
			(stroke
				(width 0.1)
				(type default)
			)
			(layer "F.Fab")
		)
		(fp_line
			(start -0.2794 -0.1016)
			(end -0.2794 0.9906)
			(stroke
				(width 0.1)
				(type default)
			)
			(layer "F.Fab")
		)
		(fp_line
			(start 0.2794 -0.1016)
			(end -0.2794 -0.1016)
			(stroke
				(width 0.1)
				(type default)
			)
			(layer "F.Fab")
		)
		(pad "1" smd rect
			(at 0 0 270)
			(size 0.508 0.508)
			(layers "F.Cu" "F.Mask" "F.Paste")
			(net "VR_PVCCIN_CPU1_PH1_OCSET")
		)
		(pad "2" smd rect
			(at 0 0.889 270)
			(size 0.508 0.508)
			(layers "F.Cu" "F.Mask" "F.Paste")
			(net "GND")
		)
		(zone
			(layer "F.Cu")
			(hatch none 0.5)
			(connect_pads
				(clearance 0)
			)
			(min_thickness 0.25)
			(keepout
				(tracks not_allowed)
				(vias allowed)
				(pads allowed)
				(copperpour not_allowed)
				(footprints allowed)
			)
			(placement
				(enabled no)
				(sheetname "")
			)
			(fill
				(thermal_gap 0.5)
				(thermal_bridge_width 0.5)
				(island_removal_mode 0)
			)
			(polygon
				(pts
					(xy 27.355292 -56.025288) (xy 27.355292 -55.517288) (xy 27.736292 -55.517288) (xy 27.736292 -56.025288)
				)
			)
		)
		(zone
			(layer "F.Cu")
			(hatch none 0.5)
			(connect_pads
				(clearance 0)
			)
			(min_thickness 0.25)
			(keepout
				(tracks allowed)
				(vias not_allowed)
				(pads allowed)
				(copperpour not_allowed)
				(footprints allowed)
			)
			(placement
				(enabled no)
				(sheetname "")
			)
			(fill
				(thermal_gap 0.5)
				(thermal_bridge_width 0.5)
				(island_removal_mode 0)
			)
			(polygon
				(pts
					(xy 27.736292 -56.025288) (xy 27.736292 -55.517288) (xy 27.355292 -55.517288) (xy 27.355292 -56.025288)
				)
			)
		)
	)
	(footprint ""
		(layer "F.Cu")
		(at 379.7173 -90.551)
		(property "Reference" "R25W72"
			(at -0.8382 -0.67818 0)
			(unlocked yes)
			(layer "F.SilkS")
			(effects
				(font
					(size 0.4064 0.254)
					(thickness 0.1524)
				)
				(justify left)
			)
		)
		(property "Value" ""
			(at 0 0 0)
			(layer "F.Fab")
			(effects
				(font
					(size 1.27 1.27)
				)
			)
		)
		(duplicate_pad_numbers_are_jumpers no)
		(fp_poly
			(pts
				(xy -0.2794 -0.1016) (xy 0.2794 -0.1016) (xy 0.2794 0.9906) (xy -0.2794 0.9906)
			)
			(stroke
				(width 0)
				(type default)
			)
			(fill no)
			(layer "F.CrtYd")
		)
		(fp_line
			(start -0.2794 -0.1016)
			(end -0.2794 0.9906)
			(stroke
				(width 0.1)
				(type default)
			)
			(layer "F.Fab")
		)
		(fp_line
			(start -0.2794 0.9906)
			(end 0.2794 0.9906)
			(stroke
				(width 0.1)
				(type default)
			)
			(layer "F.Fab")
		)
		(fp_line
			(start 0.2794 -0.1016)
			(end -0.2794 -0.1016)
			(stroke
				(width 0.1)
				(type default)
			)
			(layer "F.Fab")
		)
		(fp_line
			(start 0.2794 0.9906)
			(end 0.2794 -0.1016)
			(stroke
				(width 0.1)
				(type default)
			)
			(layer "F.Fab")
		)
		(pad "1" smd rect
			(at 0 0)
			(size 0.508 0.508)
			(layers "F.Cu" "F.Mask" "F.Paste")
			(net "LPC_LFRAME_N_CS0_N")
		)
		(pad "2" smd rect
			(at 0 0.889)
			(size 0.508 0.508)
			(layers "F.Cu" "F.Mask" "F.Paste")
			(net "LPC_LFRAME_N_CS0_R_N")
		)
		(zone
			(layer "F.Cu")
			(hatch none 0.5)
			(connect_pads
				(clearance 0)
			)
			(min_thickness 0.25)
			(keepout
				(tracks allowed)
				(vias not_allowed)
				(pads allowed)
				(copperpour not_allowed)
				(footprints allowed)
			)
			(placement
				(enabled no)
				(sheetname "")
			)
			(fill
				(thermal_gap 0.5)
				(thermal_bridge_width 0.5)
				(island_removal_mode 0)
			)
			(polygon
				(pts
					(xy 379.4633 -90.297) (xy 379.9713 -90.297) (xy 379.9713 -89.916) (xy 379.4633 -89.916)
				)
			)
		)
		(zone
			(layer "F.Cu")
			(hatch none 0.5)
			(connect_pads
				(clearance 0)
			)
			(min_thickness 0.25)
			(keepout
				(tracks not_allowed)
				(vias allowed)
				(pads allowed)
				(copperpour not_allowed)
				(footprints allowed)
			)
			(placement
				(enabled no)
				(sheetname "")
			)
			(fill
				(thermal_gap 0.5)
				(thermal_bridge_width 0.5)
				(island_removal_mode 0)
			)
			(polygon
				(pts
					(xy 379.4633 -89.916) (xy 379.9713 -89.916) (xy 379.9713 -90.297) (xy 379.4633 -90.297)
				)
			)
		)
	)
	(footprint ""
		(layer "F.Cu")
		(at 394.589 -88.2015)
		(property "Reference" "R2U9"
			(at 0 0 0)
			(layer "F.SilkS")
			(hide yes)
			(effects
				(font
					(size 1.27 1.27)
				)
			)
		)
		(property "Value" ""
			(at 0 0 0)
			(layer "F.Fab")
			(effects
				(font
					(size 1.27 1.27)
				)
			)
		)
		(duplicate_pad_numbers_are_jumpers no)
		(fp_poly
			(pts
				(xy -0.2794 -0.1016) (xy 0.2794 -0.1016) (xy 0.2794 0.9906) (xy -0.2794 0.9906)
			)
			(stroke
				(width 0)
				(type default)
			)
			(fill no)
			(layer "F.CrtYd")
		)
		(fp_line
			(start -0.2794 -0.1016)
			(end -0.2794 0.9906)
			(stroke
				(width 0.1)
				(type default)
			)
			(layer "F.Fab")
		)
		(fp_line
			(start -0.2794 0.9906)
			(end 0.2794 0.9906)
			(stroke
				(width 0.1)
				(type default)
			)
			(layer "F.Fab")
		)
		(fp_line
			(start 0.2794 -0.1016)
			(end -0.2794 -0.1016)
			(stroke
				(width 0.1)
				(type default)
			)
			(layer "F.Fab")
		)
		(fp_line
			(start 0.2794 0.9906)
			(end 0.2794 -0.1016)
			(stroke
				(width 0.1)
				(type default)
			)
			(layer "F.Fab")
		)
		(pad "1" smd rect
			(at 0 0)
			(size 0.508 0.508)
			(layers "F.Cu" "F.Mask" "F.Paste")
			(net "SMB_LAN_STBY_LVC3_SDA_R1")
		)
		(pad "2" smd rect
			(at 0 0.889)
			(size 0.508 0.508)
			(layers "F.Cu" "F.Mask" "F.Paste")
			(net "SMB_LAN_STBY_LVC3_SDA")
		)
		(zone
			(layer "F.Cu")
			(hatch none 0.5)
			(connect_pads
				(clearance 0)
			)
			(min_thickness 0.25)
			(keepout
				(tracks allowed)
				(vias not_allowed)
				(pads allowed)
				(copperpour not_allowed)
				(footprints allowed)
			)
			(placement
				(enabled no)
				(sheetname "")
			)
			(fill
				(thermal_gap 0.5)
				(thermal_bridge_width 0.5)
				(island_removal_mode 0)
			)
			(polygon
				(pts
					(xy 394.335 -87.9475) (xy 394.843 -87.9475) (xy 394.843 -87.5665) (xy 394.335 -87.5665)
				)
			)
		)
		(zone
			(layer "F.Cu")
			(hatch none 0.5)
			(connect_pads
				(clearance 0)
			)
			(min_thickness 0.25)
			(keepout
				(tracks not_allowed)
				(vias allowed)
				(pads allowed)
				(copperpour not_allowed)
				(footprints allowed)
			)
			(placement
				(enabled no)
				(sheetname "")
			)
			(fill
				(thermal_gap 0.5)
				(thermal_bridge_width 0.5)
				(island_removal_mode 0)
			)
			(polygon
				(pts
					(xy 394.335 -87.5665) (xy 394.843 -87.5665) (xy 394.843 -87.9475) (xy 394.335 -87.9475)
				)
			)
		)
	)
	(footprint ""
		(layer "F.Cu")
		(at 173.968664 -17.65681 90)
		(property "Reference" "C4F12"
			(at 0 0 90)
			(layer "F.SilkS")
			(hide yes)
			(effects
				(font
					(size 1.27 1.27)
				)
			)
		)
		(property "Value" ""
			(at 0 0 90)
			(layer "F.Fab")
			(effects
				(font
					(size 1.27 1.27)
				)
			)
		)
		(duplicate_pad_numbers_are_jumpers no)
		(fp_rect
			(start -0.3048 -0.1016)
			(end 0.3048 0.9906)
			(stroke
				(width 0)
				(type default)
			)
			(fill no)
			(layer "F.CrtYd")
		)
		(fp_line
			(start 0.3048 -0.1016)
			(end -0.3048 -0.1016)
			(stroke
				(width 0.1)
				(type default)
			)
			(layer "F.Fab")
		)
		(fp_line
			(start -0.3048 -0.1016)
			(end -0.3048 0.9906)
			(stroke
				(width 0.1)
				(type default)
			)
			(layer "F.Fab")
		)
		(fp_line
			(start 0.3048 0.9906)
			(end 0.3048 -0.1016)
			(stroke
				(width 0.1)
				(type default)
			)
			(layer "F.Fab")
		)
		(fp_line
			(start -0.3048 0.9906)
			(end 0.3048 0.9906)
			(stroke
				(width 0.1)
				(type default)
			)
			(layer "F.Fab")
		)
		(pad "1" smd rect
			(at 0 0 90)
			(size 0.508 0.508)
			(layers "F.Cu" "F.Mask" "F.Paste")
			(net "VR_PVPP_GHJ_PHASE")
		)
		(pad "2" smd rect
			(at 0 0.889 90)
			(size 0.508 0.508)
			(layers "F.Cu" "F.Mask" "F.Paste")
			(net "VR_PVPP_GHJ_SNUB")
		)
		(zone
			(layer "F.Cu")
			(hatch none 0.5)
			(connect_pads
				(clearance 0)
			)
			(min_thickness 0.25)
			(keepout
				(tracks not_allowed)
				(vias allowed)
				(pads allowed)
				(copperpour not_allowed)
				(footprints allowed)
			)
			(placement
				(enabled no)
				(sheetname "")
			)
			(fill
				(thermal_gap 0.5)
				(thermal_bridge_width 0.5)
				(island_removal_mode 0)
			)
			(polygon
				(pts
					(xy 174.222664 -17.40281) (xy 174.603664 -17.40281) (xy 174.603664 -17.91081) (xy 174.222664 -17.91081)
				)
			)
		)
		(zone
			(layer "F.Cu")
			(hatch none 0.5)
			(connect_pads
				(clearance 0)
			)
			(min_thickness 0.25)
			(keepout
				(tracks allowed)
				(vias not_allowed)
				(pads allowed)
				(copperpour not_allowed)
				(footprints allowed)
			)
			(placement
				(enabled no)
				(sheetname "")
			)
			(fill
				(thermal_gap 0.5)
				(thermal_bridge_width 0.5)
				(island_removal_mode 0)
			)
			(polygon
				(pts
					(xy 174.222664 -17.40281) (xy 174.603664 -17.40281) (xy 174.603664 -17.91081) (xy 174.222664 -17.91081)
				)
			)
		)
	)
	(footprint ""
		(layer "F.Cu")
		(at 412.4452 -111.633 90)
		(property "Reference" "R8B31"
			(at 0 0 90)
			(layer "F.SilkS")
			(hide yes)
			(effects
				(font
					(size 1.27 1.27)
				)
			)
		)
		(property "Value" ""
			(at 0 0 90)
			(layer "F.Fab")
			(effects
				(font
					(size 1.27 1.27)
				)
			)
		)
		(duplicate_pad_numbers_are_jumpers no)
		(fp_poly
			(pts
				(xy -0.2794 -0.1016) (xy 0.2794 -0.1016) (xy 0.2794 0.9906) (xy -0.2794 0.9906)
			)
			(stroke
				(width 0)
				(type default)
			)
			(fill no)
			(layer "F.CrtYd")
		)
		(fp_line
			(start 0.2794 -0.1016)
			(end -0.2794 -0.1016)
			(stroke
				(width 0.1)
				(type default)
			)
			(layer "F.Fab")
		)
		(fp_line
			(start -0.2794 -0.1016)
			(end -0.2794 0.9906)
			(stroke
				(width 0.1)
				(type default)
			)
			(layer "F.Fab")
		)
		(fp_line
			(start 0.2794 0.9906)
			(end 0.2794 -0.1016)
			(stroke
				(width 0.1)
				(type default)
			)
			(layer "F.Fab")
		)
		(fp_line
			(start -0.2794 0.9906)
			(end 0.2794 0.9906)
			(stroke
				(width 0.1)
				(type default)
			)
			(layer "F.Fab")
		)
		(pad "1" smd rect
			(at 0 0 90)
			(size 0.508 0.508)
			(layers "F.Cu" "F.Mask" "F.Paste")
			(net "P3V3_STBY")
		)
		(pad "2" smd rect
			(at 0 0.889 90)
			(size 0.508 0.508)
			(layers "F.Cu" "F.Mask" "F.Paste")
			(net "FM_THROTTLE_N")
		)
		(zone
			(layer "F.Cu")
			(hatch none 0.5)
			(connect_pads
				(clearance 0)
			)
			(min_thickness 0.25)
			(keepout
				(tracks allowed)
				(vias not_allowed)
				(pads allowed)
				(copperpour not_allowed)
				(footprints allowed)
			)
			(placement
				(enabled no)
				(sheetname "")
			)
			(fill
				(thermal_gap 0.5)
				(thermal_bridge_width 0.5)
				(island_removal_mode 0)
			)
			(polygon
				(pts
					(xy 412.6992 -111.379) (xy 412.6992 -111.887) (xy 413.0802 -111.887) (xy 413.0802 -111.379)
				)
			)
		)
		(zone
			(layer "F.Cu")
			(hatch none 0.5)
			(connect_pads
				(clearance 0)
			)
			(min_thickness 0.25)
			(keepout
				(tracks not_allowed)
				(vias allowed)
				(pads allowed)
				(copperpour not_allowed)
				(footprints allowed)
			)
			(placement
				(enabled no)
				(sheetname "")
			)
			(fill
				(thermal_gap 0.5)
				(thermal_bridge_width 0.5)
				(island_removal_mode 0)
			)
			(polygon
				(pts
					(xy 413.0802 -111.379) (xy 413.0802 -111.887) (xy 412.6992 -111.887) (xy 412.6992 -111.379)
				)
			)
		)
	)
	(footprint ""
		(layer "F.Cu")
		(at 270.628872 -73.279)
		(property "Reference" "C5D52"
			(at 0 0 0)
			(layer "F.SilkS")
			(hide yes)
			(effects
				(font
					(size 1.27 1.27)
				)
			)
		)
		(property "Value" ""
			(at 0 0 0)
			(layer "F.Fab")
			(effects
				(font
					(size 1.27 1.27)
				)
			)
		)
		(duplicate_pad_numbers_are_jumpers no)
		(fp_poly
			(pts
				(xy -0.4953 -0.2032) (xy 0.4953 -0.2032) (xy 0.4953 1.6002) (xy -0.4953 1.6002)
			)
			(stroke
				(width 0)
				(type default)
			)
			(fill no)
			(layer "F.CrtYd")
		)
		(fp_line
			(start -0.4953 -0.2032)
			(end 0.4953 -0.2032)
			(stroke
				(width 0.1)
				(type default)
			)
			(layer "F.Fab")
		)
		(fp_line
			(start -0.4953 1.6002)
			(end -0.4953 -0.2032)
			(stroke
				(width 0.1)
				(type default)
			)
			(layer "F.Fab")
		)
		(fp_line
			(start 0.4953 -0.2032)
			(end 0.4953 1.6002)
			(stroke
				(width 0.1)
				(type default)
			)
			(layer "F.Fab")
		)
		(fp_line
			(start 0.4953 1.6002)
			(end -0.4953 1.6002)
			(stroke
				(width 0.1)
				(type default)
			)
			(layer "F.Fab")
		)
		(pad "1" smd rect
			(at 0 0)
			(size 0.762 0.889)
			(layers "F.Cu" "F.Mask" "F.Paste")
			(net "PVCCMCP_CPU0")
		)
		(pad "2" smd rect
			(at 0 1.397)
			(size 0.762 0.889)
			(layers "F.Cu" "F.Mask" "F.Paste")
			(net "GND")
		)
		(zone
			(layer "F.Cu")
			(hatch none 0.5)
			(connect_pads
				(clearance 0)
			)
			(min_thickness 0.25)
			(keepout
				(tracks not_allowed)
				(vias allowed)
				(pads allowed)
				(copperpour not_allowed)
				(footprints allowed)
			)
			(placement
				(enabled no)
				(sheetname "")
			)
			(fill
				(thermal_gap 0.5)
				(thermal_bridge_width 0.5)
				(island_removal_mode 0)
			)
			(polygon
				(pts
					(xy 270.247872 -72.8345) (xy 271.009872 -72.8345) (xy 271.009872 -72.3265) (xy 270.247872 -72.3265)
				)
			)
		)
	)
	(footprint ""
		(layer "F.Cu")
		(at 444.1825 -1.143 -90)
		(property "Reference" "R2P19"
			(at 0 0 270)
			(layer "F.SilkS")
			(hide yes)
			(effects
				(font
					(size 1.27 1.27)
				)
			)
		)
		(property "Value" ""
			(at 0 0 270)
			(layer "F.Fab")
			(effects
				(font
					(size 1.27 1.27)
				)
			)
		)
		(duplicate_pad_numbers_are_jumpers no)
		(fp_poly
			(pts
				(xy -0.2794 -0.1016) (xy 0.2794 -0.1016) (xy 0.2794 0.9906) (xy -0.2794 0.9906)
			)
			(stroke
				(width 0)
				(type default)
			)
			(fill no)
			(layer "F.CrtYd")
		)
		(fp_line
			(start -0.2794 0.9906)
			(end 0.2794 0.9906)
			(stroke
				(width 0.1)
				(type default)
			)
			(layer "F.Fab")
		)
		(fp_line
			(start 0.2794 0.9906)
			(end 0.2794 -0.1016)
			(stroke
				(width 0.1)
				(type default)
			)
			(layer "F.Fab")
		)
		(fp_line
			(start -0.2794 -0.1016)
			(end -0.2794 0.9906)
			(stroke
				(width 0.1)
				(type default)
			)
			(layer "F.Fab")
		)
		(fp_line
			(start 0.2794 -0.1016)
			(end -0.2794 -0.1016)
			(stroke
				(width 0.1)
				(type default)
			)
			(layer "F.Fab")
		)
		(pad "1" smd rect
			(at 0 0 270)
			(size 0.508 0.508)
			(layers "F.Cu" "F.Mask" "F.Paste")
			(net "P3V3_STBY")
		)
		(pad "2" smd rect
			(at 0 0.889 270)
			(size 0.508 0.508)
			(layers "F.Cu" "F.Mask" "F.Paste")
			(net "FM_DIS_ADR_DLY")
		)
		(zone
			(layer "F.Cu")
			(hatch none 0.5)
			(connect_pads
				(clearance 0)
			)
			(min_thickness 0.25)
			(keepout
				(tracks not_allowed)
				(vias allowed)
				(pads allowed)
				(copperpour not_allowed)
				(footprints allowed)
			)
			(placement
				(enabled no)
				(sheetname "")
			)
			(fill
				(thermal_gap 0.5)
				(thermal_bridge_width 0.5)
				(island_removal_mode 0)
			)
			(polygon
				(pts
					(xy 443.5475 -1.397) (xy 443.5475 -0.889) (xy 443.9285 -0.889) (xy 443.9285 -1.397)
				)
			)
		)
		(zone
			(layer "F.Cu")
			(hatch none 0.5)
			(connect_pads
				(clearance 0)
			)
			(min_thickness 0.25)
			(keepout
				(tracks allowed)
				(vias not_allowed)
				(pads allowed)
				(copperpour not_allowed)
				(footprints allowed)
			)
			(placement
				(enabled no)
				(sheetname "")
			)
			(fill
				(thermal_gap 0.5)
				(thermal_bridge_width 0.5)
				(island_removal_mode 0)
			)
			(polygon
				(pts
					(xy 443.9285 -1.397) (xy 443.9285 -0.889) (xy 443.5475 -0.889) (xy 443.5475 -1.397)
				)
			)
		)
	)
)
